(kicad_pcb
	(version 20260206)
	(generator "pcbnew")
	(generator_version "10.0")
	(general
		(thickness 1.6)
		(legacy_teardrops no)
	)
	(paper "A4")
	(title_block
		(title "04192023_DAF0TMB3IC0_F0TG_MB_C_brd_V02_OCP.brd")
		(comment 1 "Grand Teton / footprints 793-798 of 8354")
	)
	(layers
		(0 "F.Cu" signal "TOP")
		(4 "In1.Cu" signal "GND")
		(6 "In2.Cu" signal "IN1")
		(8 "In3.Cu" signal "GND1")
		(10 "In4.Cu" signal "IN2")
		(12 "In5.Cu" signal "GND2")
		(14 "In6.Cu" signal "IN3")
		(16 "In7.Cu" signal "GND3")
		(18 "In8.Cu" signal "VCC")
		(20 "In9.Cu" signal "VCC1")
		(22 "In10.Cu" signal "GND4")
		(24 "In11.Cu" signal "IN4")
		(26 "In12.Cu" signal "GND5")
		(28 "In13.Cu" signal "IN5")
		(30 "In14.Cu" signal "GND6")
		(32 "In15.Cu" signal "IN6")
		(34 "In16.Cu" signal "GND7")
		(2 "B.Cu" signal "BOTTOM")
		(9 "F.Adhes" user "F.Adhesive")
		(11 "B.Adhes" user "B.Adhesive")
		(13 "F.Paste" user "Package Geometry/Pastemask Top")
		(15 "B.Paste" user "Package Geometry/Pastemask Bottom")
		(5 "F.SilkS" user "Ref Des/Silkscreen Top")
		(7 "B.SilkS" user "Ref Des/Silkscreen Bottom")
		(1 "F.Mask" user "Board Geometry/Soldermask Top")
		(3 "B.Mask" user "Board Geometry/Soldermask Bottom")
		(17 "Dwgs.User" user "User.Drawings")
		(19 "Cmts.User" user "User.Comments")
		(21 "Eco1.User" user "User.Eco1")
		(23 "Eco2.User" user "User.Eco2")
		(25 "Edge.Cuts" user "Board Geometry/Outline")
		(27 "Margin" user)
		(31 "F.CrtYd" user "Package Geometry/Place Bound Top")
		(29 "B.CrtYd" user "Package Geometry/Place Bound Bottom")
		(35 "F.Fab" user "Ref Des/Assembly Top")
		(33 "B.Fab" user "Ref Des/Assembly Bottom")
	)
	(footprint ""
		(layer "F.Cu")
		(at 185.801 -100.294948 -90)
		(property "Reference" "R1190"
			(at 0 0 270)
			(layer "F.SilkS")
			(hide yes)
			(effects
				(font
					(size 1.27 1.27)
				)
			)
		)
		(property "Value" ""
			(at 0 0 270)
			(layer "F.Fab")
			(effects
				(font
					(size 1.27 1.27)
				)
			)
		)
		(duplicate_pad_numbers_are_jumpers no)
		(fp_line
			(start -0.7874 0.4064)
			(end -0.7874 -0.4064)
			(stroke
				(width 0.1524)
				(type default)
			)
			(layer "F.SilkS")
		)
		(fp_line
			(start 0.7874 0.4064)
			(end -0.7874 0.4064)
			(stroke
				(width 0.1524)
				(type default)
			)
			(layer "F.SilkS")
		)
		(fp_line
			(start -0.7874 -0.4064)
			(end 0.7874 -0.4064)
			(stroke
				(width 0.1524)
				(type default)
			)
			(layer "F.SilkS")
		)
		(fp_line
			(start 0.7874 -0.4064)
			(end 0.7874 0.4064)
			(stroke
				(width 0.1524)
				(type default)
			)
			(layer "F.SilkS")
		)
		(fp_line
			(start -0.67945 0.3048)
			(end -0.67945 -0.305054)
			(stroke
				(width 0.1)
				(type default)
			)
			(layer "F.Fab")
		)
		(fp_line
			(start -0.12065 0.3048)
			(end -0.67945 0.3048)
			(stroke
				(width 0.1)
				(type default)
			)
			(layer "F.Fab")
		)
		(fp_line
			(start 0.120396 0.3048)
			(end 0.120396 0.2794)
			(stroke
				(width 0.1)
				(type default)
			)
			(layer "F.Fab")
		)
		(fp_line
			(start 0.67945 0.3048)
			(end 0.120396 0.3048)
			(stroke
				(width 0.1)
				(type default)
			)
			(layer "F.Fab")
		)
		(fp_line
			(start -0.12065 0.2794)
			(end -0.12065 0.3048)
			(stroke
				(width 0.1)
				(type default)
			)
			(layer "F.Fab")
		)
		(fp_line
			(start 0.120396 0.2794)
			(end -0.12065 0.2794)
			(stroke
				(width 0.1)
				(type default)
			)
			(layer "F.Fab")
		)
		(fp_line
			(start -0.12065 -0.2794)
			(end 0.12065 -0.2794)
			(stroke
				(width 0.1)
				(type default)
			)
			(layer "F.Fab")
		)
		(fp_line
			(start 0.12065 -0.2794)
			(end 0.12065 -0.3048)
			(stroke
				(width 0.1)
				(type default)
			)
			(layer "F.Fab")
		)
		(fp_line
			(start 0.12065 -0.3048)
			(end 0.67945 -0.3048)
			(stroke
				(width 0.1)
				(type default)
			)
			(layer "F.Fab")
		)
		(fp_line
			(start 0.67945 -0.3048)
			(end 0.67945 0.3048)
			(stroke
				(width 0.1)
				(type default)
			)
			(layer "F.Fab")
		)
		(fp_line
			(start -0.67945 -0.305054)
			(end -0.12065 -0.305054)
			(stroke
				(width 0.1)
				(type default)
			)
			(layer "F.Fab")
		)
		(fp_line
			(start -0.12065 -0.305054)
			(end -0.12065 -0.2794)
			(stroke
				(width 0.1)
				(type default)
			)
			(layer "F.Fab")
		)
		(pad "1" smd circle
			(at -0.40005 0 270)
			(size 0 0)
			(layers "F.Cu" "F.Mask" "F.Paste")
			(net "PVDD11_S3_P1_PMALERT")
		)
		(pad "2" smd circle
			(at 0.40005 0 270)
			(size 0 0)
			(layers "F.Cu" "F.Mask" "F.Paste")
			(net "P3V3_AUX")
		)
	)
	(footprint ""
		(layer "F.Cu")
		(at 167.112442 -116.26977)
		(property "Reference" "R6136"
			(at 0 0 0)
			(layer "F.SilkS")
			(hide yes)
			(effects
				(font
					(size 1.27 1.27)
				)
			)
		)
		(property "Value" ""
			(at 0 0 0)
			(layer "F.Fab")
			(effects
				(font
					(size 1.27 1.27)
				)
			)
		)
		(duplicate_pad_numbers_are_jumpers no)
		(fp_line
			(start -0.7874 -0.4064)
			(end 0.7874 -0.4064)
			(stroke
				(width 0.1524)
				(type default)
			)
			(layer "F.SilkS")
		)
		(fp_line
			(start -0.7874 0.4064)
			(end -0.7874 -0.4064)
			(stroke
				(width 0.1524)
				(type default)
			)
			(layer "F.SilkS")
		)
		(fp_line
			(start 0.7874 -0.4064)
			(end 0.7874 0.4064)
			(stroke
				(width 0.1524)
				(type default)
			)
			(layer "F.SilkS")
		)
		(fp_line
			(start 0.7874 0.4064)
			(end -0.7874 0.4064)
			(stroke
				(width 0.1524)
				(type default)
			)
			(layer "F.SilkS")
		)
		(fp_line
			(start -0.67945 -0.305054)
			(end -0.12065 -0.305054)
			(stroke
				(width 0.1)
				(type default)
			)
			(layer "F.Fab")
		)
		(fp_line
			(start -0.67945 0.3048)
			(end -0.67945 -0.305054)
			(stroke
				(width 0.1)
				(type default)
			)
			(layer "F.Fab")
		)
		(fp_line
			(start -0.12065 -0.305054)
			(end -0.12065 -0.2794)
			(stroke
				(width 0.1)
				(type default)
			)
			(layer "F.Fab")
		)
		(fp_line
			(start -0.12065 -0.2794)
			(end 0.12065 -0.2794)
			(stroke
				(width 0.1)
				(type default)
			)
			(layer "F.Fab")
		)
		(fp_line
			(start -0.12065 0.2794)
			(end -0.12065 0.3048)
			(stroke
				(width 0.1)
				(type default)
			)
			(layer "F.Fab")
		)
		(fp_line
			(start -0.12065 0.3048)
			(end -0.67945 0.3048)
			(stroke
				(width 0.1)
				(type default)
			)
			(layer "F.Fab")
		)
		(fp_line
			(start 0.120396 0.2794)
			(end -0.12065 0.2794)
			(stroke
				(width 0.1)
				(type default)
			)
			(layer "F.Fab")
		)
		(fp_line
			(start 0.120396 0.3048)
			(end 0.120396 0.2794)
			(stroke
				(width 0.1)
				(type default)
			)
			(layer "F.Fab")
		)
		(fp_line
			(start 0.12065 -0.3048)
			(end 0.67945 -0.3048)
			(stroke
				(width 0.1)
				(type default)
			)
			(layer "F.Fab")
		)
		(fp_line
			(start 0.12065 -0.2794)
			(end 0.12065 -0.3048)
			(stroke
				(width 0.1)
				(type default)
			)
			(layer "F.Fab")
		)
		(fp_line
			(start 0.67945 -0.3048)
			(end 0.67945 0.3048)
			(stroke
				(width 0.1)
				(type default)
			)
			(layer "F.Fab")
		)
		(fp_line
			(start 0.67945 0.3048)
			(end 0.120396 0.3048)
			(stroke
				(width 0.1)
				(type default)
			)
			(layer "F.Fab")
		)
		(pad "1" smd circle
			(at -0.40005 0)
			(size 0 0)
			(layers "F.Cu" "F.Mask" "F.Paste")
			(net "P3V3_AUX")
		)
		(pad "2" smd circle
			(at 0.40005 0)
			(size 0 0)
			(layers "F.Cu" "F.Mask" "F.Paste")
			(net "FM_BOARD_BMC_SKU_ID4")
		)
	)
	(footprint ""
		(layer "F.Cu")
		(at 118.617746 -53.49748 180)
		(property "Reference" "R6298"
			(at 0 0 180)
			(layer "F.SilkS")
			(hide yes)
			(effects
				(font
					(size 1.27 1.27)
				)
			)
		)
		(property "Value" ""
			(at 0 0 180)
			(layer "F.Fab")
			(effects
				(font
					(size 1.27 1.27)
				)
			)
		)
		(duplicate_pad_numbers_are_jumpers no)
		(fp_line
			(start 0.7874 0.4064)
			(end -0.7874 0.4064)
			(stroke
				(width 0.1524)
				(type default)
			)
			(layer "F.SilkS")
		)
		(fp_line
			(start 0.7874 -0.4064)
			(end 0.7874 0.4064)
			(stroke
				(width 0.1524)
				(type default)
			)
			(layer "F.SilkS")
		)
		(fp_line
			(start -0.7874 0.4064)
			(end -0.7874 -0.4064)
			(stroke
				(width 0.1524)
				(type default)
			)
			(layer "F.SilkS")
		)
		(fp_line
			(start -0.7874 -0.4064)
			(end 0.7874 -0.4064)
			(stroke
				(width 0.1524)
				(type default)
			)
			(layer "F.SilkS")
		)
		(fp_line
			(start 0.67945 0.3048)
			(end 0.120396 0.3048)
			(stroke
				(width 0.1)
				(type default)
			)
			(layer "F.Fab")
		)
		(fp_line
			(start 0.67945 -0.3048)
			(end 0.67945 0.3048)
			(stroke
				(width 0.1)
				(type default)
			)
			(layer "F.Fab")
		)
		(fp_line
			(start 0.12065 -0.2794)
			(end 0.12065 -0.3048)
			(stroke
				(width 0.1)
				(type default)
			)
			(layer "F.Fab")
		)
		(fp_line
			(start 0.12065 -0.3048)
			(end 0.67945 -0.3048)
			(stroke
				(width 0.1)
				(type default)
			)
			(layer "F.Fab")
		)
		(fp_line
			(start 0.120396 0.3048)
			(end 0.120396 0.2794)
			(stroke
				(width 0.1)
				(type default)
			)
			(layer "F.Fab")
		)
		(fp_line
			(start 0.120396 0.2794)
			(end -0.12065 0.2794)
			(stroke
				(width 0.1)
				(type default)
			)
			(layer "F.Fab")
		)
		(fp_line
			(start -0.12065 0.3048)
			(end -0.67945 0.3048)
			(stroke
				(width 0.1)
				(type default)
			)
			(layer "F.Fab")
		)
		(fp_line
			(start -0.12065 0.2794)
			(end -0.12065 0.3048)
			(stroke
				(width 0.1)
				(type default)
			)
			(layer "F.Fab")
		)
		(fp_line
			(start -0.12065 -0.2794)
			(end 0.12065 -0.2794)
			(stroke
				(width 0.1)
				(type default)
			)
			(layer "F.Fab")
		)
		(fp_line
			(start -0.12065 -0.305054)
			(end -0.12065 -0.2794)
			(stroke
				(width 0.1)
				(type default)
			)
			(layer "F.Fab")
		)
		(fp_line
			(start -0.67945 0.3048)
			(end -0.67945 -0.305054)
			(stroke
				(width 0.1)
				(type default)
			)
			(layer "F.Fab")
		)
		(fp_line
			(start -0.67945 -0.305054)
			(end -0.12065 -0.305054)
			(stroke
				(width 0.1)
				(type default)
			)
			(layer "F.Fab")
		)
		(pad "1" smd circle
			(at -0.40005 0 180)
			(size 0 0)
			(layers "F.Cu" "F.Mask" "F.Paste")
			(net "P3V3_AUX")
		)
		(pad "2" smd circle
			(at 0.40005 0 180)
			(size 0 0)
			(layers "F.Cu" "F.Mask" "F.Paste")
			(net "USB_HUB2_MRP_I2C_SLV_CFG1")
		)
	)
	(footprint ""
		(layer "F.Cu")
		(at 124.633228 -50.169064 180)
		(property "Reference" "R4453"
			(at 0 0 180)
			(layer "F.SilkS")
			(hide yes)
			(effects
				(font
					(size 1.27 1.27)
				)
			)
		)
		(property "Value" ""
			(at 0 0 180)
			(layer "F.Fab")
			(effects
				(font
					(size 1.27 1.27)
				)
			)
		)
		(duplicate_pad_numbers_are_jumpers no)
		(fp_line
			(start 0.7874 0.4064)
			(end -0.7874 0.4064)
			(stroke
				(width 0.1524)
				(type default)
			)
			(layer "F.SilkS")
		)
		(fp_line
			(start 0.7874 -0.4064)
			(end 0.7874 0.4064)
			(stroke
				(width 0.1524)
				(type default)
			)
			(layer "F.SilkS")
		)
		(fp_line
			(start -0.7874 0.4064)
			(end -0.7874 -0.4064)
			(stroke
				(width 0.1524)
				(type default)
			)
			(layer "F.SilkS")
		)
		(fp_line
			(start -0.7874 -0.4064)
			(end 0.7874 -0.4064)
			(stroke
				(width 0.1524)
				(type default)
			)
			(layer "F.SilkS")
		)
		(fp_line
			(start 0.67945 0.3048)
			(end 0.120396 0.3048)
			(stroke
				(width 0.1)
				(type default)
			)
			(layer "F.Fab")
		)
		(fp_line
			(start 0.67945 -0.3048)
			(end 0.67945 0.3048)
			(stroke
				(width 0.1)
				(type default)
			)
			(layer "F.Fab")
		)
		(fp_line
			(start 0.12065 -0.2794)
			(end 0.12065 -0.3048)
			(stroke
				(width 0.1)
				(type default)
			)
			(layer "F.Fab")
		)
		(fp_line
			(start 0.12065 -0.3048)
			(end 0.67945 -0.3048)
			(stroke
				(width 0.1)
				(type default)
			)
			(layer "F.Fab")
		)
		(fp_line
			(start 0.120396 0.3048)
			(end 0.120396 0.2794)
			(stroke
				(width 0.1)
				(type default)
			)
			(layer "F.Fab")
		)
		(fp_line
			(start 0.120396 0.2794)
			(end -0.12065 0.2794)
			(stroke
				(width 0.1)
				(type default)
			)
			(layer "F.Fab")
		)
		(fp_line
			(start -0.12065 0.3048)
			(end -0.67945 0.3048)
			(stroke
				(width 0.1)
				(type default)
			)
			(layer "F.Fab")
		)
		(fp_line
			(start -0.12065 0.2794)
			(end -0.12065 0.3048)
			(stroke
				(width 0.1)
				(type default)
			)
			(layer "F.Fab")
		)
		(fp_line
			(start -0.12065 -0.2794)
			(end 0.12065 -0.2794)
			(stroke
				(width 0.1)
				(type default)
			)
			(layer "F.Fab")
		)
		(fp_line
			(start -0.12065 -0.305054)
			(end -0.12065 -0.2794)
			(stroke
				(width 0.1)
				(type default)
			)
			(layer "F.Fab")
		)
		(fp_line
			(start -0.67945 0.3048)
			(end -0.67945 -0.305054)
			(stroke
				(width 0.1)
				(type default)
			)
			(layer "F.Fab")
		)
		(fp_line
			(start -0.67945 -0.305054)
			(end -0.12065 -0.305054)
			(stroke
				(width 0.1)
				(type default)
			)
			(layer "F.Fab")
		)
		(pad "1" smd circle
			(at -0.40005 0 180)
			(size 0 0)
			(layers "F.Cu" "F.Mask" "F.Paste")
			(net "RST_USB_CPU0_HUB1_R_N")
		)
		(pad "2" smd circle
			(at 0.40005 0 180)
			(size 0 0)
			(layers "F.Cu" "F.Mask" "F.Paste")
			(net "GND")
		)
	)
	(footprint ""
		(layer "F.Cu")
		(at 389.497316 -22.789134 90)
		(property "Reference" "R42"
			(at 0 0 90)
			(layer "F.SilkS")
			(hide yes)
			(effects
				(font
					(size 1.27 1.27)
				)
			)
		)
		(property "Value" ""
			(at 0 0 90)
			(layer "F.Fab")
			(effects
				(font
					(size 1.27 1.27)
				)
			)
		)
		(duplicate_pad_numbers_are_jumpers no)
		(fp_line
			(start 0.7874 -0.4064)
			(end 0.7874 0.011684)
			(stroke
				(width 0.1524)
				(type default)
			)
			(layer "F.SilkS")
		)
		(fp_line
			(start -0.7874 -0.4064)
			(end 0.7874 -0.4064)
			(stroke
				(width 0.1524)
				(type default)
			)
			(layer "F.SilkS")
		)
		(fp_line
			(start -0.7874 0.011684)
			(end -0.7874 -0.4064)
			(stroke
				(width 0.1524)
				(type default)
			)
			(layer "F.SilkS")
		)
		(fp_line
			(start -0.12065 -0.305054)
			(end -0.12065 -0.2794)
			(stroke
				(width 0.1)
				(type default)
			)
			(layer "F.Fab")
		)
		(fp_line
			(start -0.67945 -0.305054)
			(end -0.12065 -0.305054)
			(stroke
				(width 0.1)
				(type default)
			)
			(layer "F.Fab")
		)
		(fp_line
			(start 0.67945 -0.3048)
			(end 0.67945 0.3048)
			(stroke
				(width 0.1)
				(type default)
			)
			(layer "F.Fab")
		)
		(fp_line
			(start 0.12065 -0.3048)
			(end 0.67945 -0.3048)
			(stroke
				(width 0.1)
				(type default)
			)
			(layer "F.Fab")
		)
		(fp_line
			(start 0.12065 -0.2794)
			(end 0.12065 -0.3048)
			(stroke
				(width 0.1)
				(type default)
			)
			(layer "F.Fab")
		)
		(fp_line
			(start -0.12065 -0.2794)
			(end 0.12065 -0.2794)
			(stroke
				(width 0.1)
				(type default)
			)
			(layer "F.Fab")
		)
		(fp_line
			(start 0.120396 0.2794)
			(end -0.12065 0.2794)
			(stroke
				(width 0.1)
				(type default)
			)
			(layer "F.Fab")
		)
		(fp_line
			(start -0.12065 0.2794)
			(end -0.12065 0.3048)
			(stroke
				(width 0.1)
				(type default)
			)
			(layer "F.Fab")
		)
		(fp_line
			(start 0.67945 0.3048)
			(end 0.120396 0.3048)
			(stroke
				(width 0.1)
				(type default)
			)
			(layer "F.Fab")
		)
		(fp_line
			(start 0.120396 0.3048)
			(end 0.120396 0.2794)
			(stroke
				(width 0.1)
				(type default)
			)
			(layer "F.Fab")
		)
		(fp_line
			(start -0.12065 0.3048)
			(end -0.67945 0.3048)
			(stroke
				(width 0.1)
				(type default)
			)
			(layer "F.Fab")
		)
		(fp_line
			(start -0.67945 0.3048)
			(end -0.67945 -0.305054)
			(stroke
				(width 0.1)
				(type default)
			)
			(layer "F.Fab")
		)
		(pad "1" smd circle
			(at -0.40005 0 90)
			(size 0 0)
			(layers "F.Cu" "F.Mask" "F.Paste")
			(net "USB2_P11_DN")
		)
		(pad "2" smd circle
			(at 0.40005 0 90)
			(size 0 0)
			(layers "F.Cu" "F.Mask" "F.Paste")
			(net "USB2_CPU0_P11_DN")
		)
	)
	(footprint ""
		(layer "F.Cu")
		(at 158.82874 -44.985686 90)
		(property "Reference" "R2476"
			(at 0 0 90)
			(layer "F.SilkS")
			(hide yes)
			(effects
				(font
					(size 1.27 1.27)
				)
			)
		)
		(property "Value" ""
			(at 0 0 90)
			(layer "F.Fab")
			(effects
				(font
					(size 1.27 1.27)
				)
			)
		)
		(duplicate_pad_numbers_are_jumpers no)
		(fp_line
			(start 0.7874 -0.4064)
			(end 0.7874 0.4064)
			(stroke
				(width 0.1524)
				(type default)
			)
			(layer "F.SilkS")
		)
		(fp_line
			(start -0.7874 -0.4064)
			(end 0.7874 -0.4064)
			(stroke
				(width 0.1524)
				(type default)
			)
			(layer "F.SilkS")
		)
		(fp_line
			(start 0.7874 0.4064)
			(end -0.7874 0.4064)
			(stroke
				(width 0.1524)
				(type default)
			)
			(layer "F.SilkS")
		)
		(fp_line
			(start -0.7874 0.4064)
			(end -0.7874 -0.4064)
			(stroke
				(width 0.1524)
				(type default)
			)
			(layer "F.SilkS")
		)
		(fp_line
			(start -0.12065 -0.305054)
			(end -0.12065 -0.2794)
			(stroke
				(width 0.1)
				(type default)
			)
			(layer "F.Fab")
		)
		(fp_line
			(start -0.67945 -0.305054)
			(end -0.12065 -0.305054)
			(stroke
				(width 0.1)
				(type default)
			)
			(layer "F.Fab")
		)
		(fp_line
			(start 0.67945 -0.3048)
			(end 0.67945 0.3048)
			(stroke
				(width 0.1)
				(type default)
			)
			(layer "F.Fab")
		)
		(fp_line
			(start 0.12065 -0.3048)
			(end 0.67945 -0.3048)
			(stroke
				(width 0.1)
				(type default)
			)
			(layer "F.Fab")
		)
		(fp_line
			(start 0.12065 -0.2794)
			(end 0.12065 -0.3048)
			(stroke
				(width 0.1)
				(type default)
			)
			(layer "F.Fab")
		)
		(fp_line
			(start -0.12065 -0.2794)
			(end 0.12065 -0.2794)
			(stroke
				(width 0.1)
				(type default)
			)
			(layer "F.Fab")
		)
		(fp_line
			(start 0.120396 0.2794)
			(end -0.12065 0.2794)
			(stroke
				(width 0.1)
				(type default)
			)
			(layer "F.Fab")
		)
		(fp_line
			(start -0.12065 0.2794)
			(end -0.12065 0.3048)
			(stroke
				(width 0.1)
				(type default)
			)
			(layer "F.Fab")
		)
		(fp_line
			(start 0.67945 0.3048)
			(end 0.120396 0.3048)
			(stroke
				(width 0.1)
				(type default)
			)
			(layer "F.Fab")
		)
		(fp_line
			(start 0.120396 0.3048)
			(end 0.120396 0.2794)
			(stroke
				(width 0.1)
				(type default)
			)
			(layer "F.Fab")
		)
		(fp_line
			(start -0.12065 0.3048)
			(end -0.67945 0.3048)
			(stroke
				(width 0.1)
				(type default)
			)
			(layer "F.Fab")
		)
		(fp_line
			(start -0.67945 0.3048)
			(end -0.67945 -0.305054)
			(stroke
				(width 0.1)
				(type default)
			)
			(layer "F.Fab")
		)
		(pad "1" smd circle
			(at -0.40005 0 90)
			(size 0 0)
			(layers "F.Cu" "F.Mask" "F.Paste")
			(net "SMB_PCIE_M2_0_EN")
		)
		(pad "2" smd circle
			(at 0.40005 0 90)
			(size 0 0)
			(layers "F.Cu" "F.Mask" "F.Paste")
			(net "PWRGD_P1V8_AUX_R")
		)
	)
)
